FILE_TYPE = CONNECTIVITY;
{Allegro Design Entry HDL 17.2-2016 S081 (4005846) 1/11/2022}
"PAGE_NUMBER" = 92;
0"NC";
1"P3V3_AUX\g";
2"P12V_S3_AUX_CPU0_NVDIMM\g";
3"P3V3_AUX\g";
4"P12V_S3_AUX_CPU0_NVDIMM\g";
5"GND\g";
6"GND\g";
7"GND\g";
8"GND\g";
9"GND\g";
10"M_F_CPU0_SA_CB<7:0>";
11"M_F_CPU0_SB_CB<7:0>";
12"M_F_CPU0_SA_CA<6:0>";
13"M_F_CPU0_SB_CA<6:0>";
14"M_F_CPU0_SA_DQ<31:0>";
15"M_F_CPU0_SB_DQ<31:0>";
16"M_F_CPU0_SB_DQS_DP<9:0>";
17"M_F_CPU0_SA_DQS_DP<9:0>";
18"M_F_CPU0_SB_DQS_DN<9:0>";
19"M_F_CPU0_SA_DQS_DN<9:0>";
20"PD_CHF_CPU0_DIMM1_SAA";
21"I3C_SPD_DDREFGH_CPU0_LVC1_SDA";
22"I3C_SPD_DDREFGH_CPU0_LVC1_SCL_R3";
23"M_F_CPU0_ALERT_N";
24"RST_M_EF_CPU0_FPGA_N";
25"I3C_SPD_DDREFGH_CPU0_LVC1_SCL";
26"PWRGD_CHF_CPU0_DIMM1";
27"TP_CHF_CPU0_DIMM1_FRU_6";
28"M_F_CPU0_SB_DQS_DN<2>";
29"M_F_CPU0_SA_DQS_DN<9>";
30"M_F_CPU0_SA_DQS_DN<8>";
31"M_F_CPU0_SA_DQS_DN<7>";
32"M_F_CPU0_SA_DQS_DN<6>";
33"M_F_CPU0_SA_DQS_DN<4>";
34"M_F_CPU0_SA_DQS_DN<5>";
35"M_F_CPU0_SA_DQS_DN<3>";
36"M_F_CPU0_SA_DQS_DN<2>";
37"M_F_CPU0_SA_DQS_DN<1>";
38"M_F_CPU0_SA_DQS_DN<0>";
39"M_F_CPU0_SB_DQS_DN<9>";
40"M_F_CPU0_SB_DQS_DN<8>";
41"M_F_CPU0_SB_DQS_DN<7>";
42"M_F_CPU0_SB_DQS_DN<6>";
43"M_F_CPU0_SB_DQS_DN<5>";
44"M_F_CPU0_SB_DQS_DN<3>";
45"M_F_CPU0_SB_DQS_DN<4>";
46"M_F_CPU0_SB_DQS_DN<1>";
47"M_F_CPU0_SB_DQS_DN<0>";
48"M_F_CPU0_SA_DQS_DP<9>";
49"M_F_CPU0_SA_DQS_DP<8>";
50"M_F_CPU0_SA_DQS_DP<7>";
51"M_F_CPU0_SA_DQS_DP<6>";
52"M_F_CPU0_SA_DQS_DP<5>";
53"M_F_CPU0_SA_DQS_DP<4>";
54"M_F_CPU0_SA_DQS_DP<3>";
55"M_F_CPU0_SA_DQS_DP<2>";
56"M_F_CPU0_SA_DQS_DP<1>";
57"M_F_CPU0_SA_DQS_DP<0>";
58"M_F_CPU0_SB_DQS_DP<9>";
59"M_F_CPU0_SB_DQS_DP<8>";
60"M_F_CPU0_SB_DQS_DP<7>";
61"M_F_CPU0_SB_DQS_DP<6>";
62"M_F_CPU0_SB_DQS_DP<5>";
63"M_F_CPU0_SB_DQS_DP<4>";
64"M_F_CPU0_SB_DQS_DP<3>";
65"M_F_CPU0_SB_DQS_DP<2>";
66"M_F_CPU0_SB_DQS_DP<1>";
67"M_F_CPU0_SB_DQS_DP<0>";
68"TP_CHF_CPU0_DIMM1_FRU_3";
69"M_F_CPU0_SA_DQ<30>";
70"M_F_CPU0_SA_DQ<31>";
71"M_F_CPU0_SA_DQ<9>";
72"M_F_CPU0_SA_DQ<12>";
73"M_F_CPU0_SA_CB<4>";
74"M_F_CPU0_SB_DQ<19>";
75"M_F_CPU0_SB_DQ<6>";
76"TP_CHF_CPU0_DIMM1_FRU_0";
77"M_F_CPU0_SB_RSP<0>";
78"M_F_CPU0_SB_DQ<1>";
79"TP_CHF_CPU0_DIMM1_FRU_1";
80"TP_CHF_CPU0_DIMM1_FRU_2";
81"TP_CHF_CPU0_DIMM1_FRU_4";
82"TP_CHF_CPU0_DIMM1_FRU_5";
83"M_F_CPU0_SB_PAR";
84"M_F_CPU0_SA_PAR";
85"M_F_CPU0_SA_RSP<0>";
86"M_F_CPU0_SB_DQ<0>";
87"M_F_CPU0_SB_DQ<2>";
88"M_F_CPU0_SB_DQ<3>";
89"M_F_CPU0_SB_DQ<4>";
90"M_F_CPU0_SB_DQ<5>";
91"M_F_CPU0_SB_DQ<7>";
92"M_F_CPU0_SB_DQ<8>";
93"M_F_CPU0_SB_DQ<9>";
94"M_F_CPU0_SB_DQ<10>";
95"M_F_CPU0_SB_DQ<11>";
96"M_F_CPU0_SB_DQ<12>";
97"M_F_CPU0_SB_DQ<13>";
98"M_F_CPU0_SB_DQ<14>";
99"M_F_CPU0_SB_DQ<15>";
100"M_F_CPU0_SB_DQ<16>";
101"M_F_CPU0_SB_DQ<17>";
102"M_F_CPU0_SB_DQ<18>";
103"M_F_CPU0_SB_DQ<20>";
104"M_F_CPU0_SB_DQ<21>";
105"M_F_CPU0_SB_DQ<22>";
106"M_F_CPU0_SB_DQ<23>";
107"M_F_CPU0_SB_DQ<24>";
108"M_F_CPU0_SB_DQ<25>";
109"M_F_CPU0_SB_DQ<26>";
110"M_F_CPU0_SB_DQ<27>";
111"M_F_CPU0_SB_DQ<28>";
112"M_F_CPU0_SB_DQ<29>";
113"M_F_CPU0_SB_DQ<30>";
114"M_F_CPU0_SB_DQ<31>";
115"M_F_CPU0_SA_DQ<0>";
116"M_F_CPU0_SA_DQ<1>";
117"M_F_CPU0_SA_DQ<2>";
118"M_F_CPU0_SA_DQ<3>";
119"M_F_CPU0_SA_DQ<4>";
120"M_F_CPU0_SA_DQ<5>";
121"M_F_CPU0_SA_DQ<6>";
122"M_F_CPU0_SA_DQ<7>";
123"M_F_CPU0_SA_DQ<8>";
124"M_F_CPU0_SA_DQ<10>";
125"M_F_CPU0_SA_DQ<11>";
126"M_F_CPU0_SA_DQ<13>";
127"M_F_CPU0_SA_DQ<14>";
128"M_F_CPU0_SA_DQ<15>";
129"M_F_CPU0_SA_DQ<16>";
130"M_F_CPU0_SA_DQ<17>";
131"M_F_CPU0_SA_DQ<18>";
132"M_F_CPU0_SA_DQ<19>";
133"M_F_CPU0_SA_DQ<20>";
134"M_F_CPU0_SA_DQ<21>";
135"M_F_CPU0_SA_DQ<22>";
136"M_F_CPU0_SA_DQ<23>";
137"M_F_CPU0_SA_DQ<24>";
138"M_F_CPU0_SA_DQ<25>";
139"M_F_CPU0_SA_DQ<26>";
140"M_F_CPU0_SA_DQ<27>";
141"M_F_CPU0_SA_DQ<28>";
142"M_F_CPU0_SA_DQ<29>";
143"M_F_CPU0_SB_CS_N<1>";
144"M_F_CPU0_SA_CS_N<1>";
145"M_F_CPU0_SB_CS_N<0>";
146"M_F_CPU0_SA_CS_N<0>";
147"M_F_CPU0_CLK_DP<0>";
148"M_F_CPU0_CLK_DN<0>";
149"M_F_CPU0_SB_CB<0>";
150"M_F_CPU0_SB_CB<1>";
151"M_F_CPU0_SB_CB<2>";
152"M_F_CPU0_SB_CB<3>";
153"M_F_CPU0_SB_CB<4>";
154"M_F_CPU0_SB_CB<5>";
155"M_F_CPU0_SB_CB<6>";
156"M_F_CPU0_SA_CB<0>";
157"M_F_CPU0_SA_CB<2>";
158"M_F_CPU0_SA_CB<3>";
159"M_F_CPU0_SA_CB<5>";
160"M_F_CPU0_SA_CB<6>";
161"M_F_CPU0_SB_CA<6>";
162"M_F_CPU0_SA_CA<6>";
163"M_F_CPU0_SB_CA<5>";
164"M_F_CPU0_SA_CA<5>";
165"M_F_CPU0_SB_CA<4>";
166"M_F_CPU0_SA_CA<4>";
167"M_F_CPU0_SB_CA<3>";
168"M_F_CPU0_SA_CA<3>";
169"M_F_CPU0_SB_CA<2>";
170"M_F_CPU0_SA_CA<2>";
171"M_F_CPU0_SB_CA<1>";
172"M_F_CPU0_SA_CA<1>";
173"M_F_CPU0_SB_CA<0>";
174"M_F_CPU0_SA_CA<0>";
175"M_F_CPU0_SB_CB<7>";
176"M_F_CPU0_SA_CB<1>";
177"M_F_CPU0_SA_CB<7>";
178"PD_CHF_CPU0_DIMM1_SAA";
%"UNIVERSAL_GND"
"1","(-2525,25)","0","logical_power","I1";
;
CDS_LIB"logical_power"
HDL_POWER"GND";
"A"9;
%"TAP"
"1","(-1100,3450)","0","standard","I100";
;
CDS_LIB"standard"
BODY_TYPE"PLUMBING"
HDL_TAP"TRUE";
"B \NAC \NWC"14;
"S \NAC"
BN"12"72;
%"TAP"
"1","(-1100,3550)","0","standard","I101";
;
CDS_LIB"standard"
BODY_TYPE"PLUMBING"
HDL_TAP"TRUE";
"B \NAC \NWC"14;
"S \NAC"
BN"14"127;
%"TAP"
"1","(-1100,3500)","0","standard","I102";
;
CDS_LIB"standard"
BODY_TYPE"PLUMBING"
HDL_TAP"TRUE";
"B \NAC \NWC"14;
"S \NAC"
BN"13"126;
%"TAP"
"1","(-1100,3700)","0","standard","I103";
;
CDS_LIB"standard"
BODY_TYPE"PLUMBING"
HDL_TAP"TRUE";
"B \NAC \NWC"14;
"S \NAC"
BN"17"130;
%"TAP"
"1","(-1100,3600)","0","standard","I104";
;
CDS_LIB"standard"
BODY_TYPE"PLUMBING"
HDL_TAP"TRUE";
"B \NAC \NWC"14;
"S \NAC"
BN"15"128;
%"TAP"
"1","(-1100,3650)","0","standard","I105";
;
CDS_LIB"standard"
BODY_TYPE"PLUMBING"
HDL_TAP"TRUE";
"B \NAC \NWC"14;
"S \NAC"
BN"16"129;
%"TAP"
"1","(-1100,3800)","0","standard","I106";
;
CDS_LIB"standard"
BODY_TYPE"PLUMBING"
HDL_TAP"TRUE";
"B \NAC \NWC"14;
"S \NAC"
BN"19"132;
%"TAP"
"1","(-1100,3750)","0","standard","I107";
;
CDS_LIB"standard"
BODY_TYPE"PLUMBING"
HDL_TAP"TRUE";
"B \NAC \NWC"14;
"S \NAC"
BN"18"131;
%"TAP"
"1","(-1100,3950)","0","standard","I108";
;
CDS_LIB"standard"
BODY_TYPE"PLUMBING"
HDL_TAP"TRUE";
"B \NAC \NWC"14;
"S \NAC"
BN"22"135;
%"TAP"
"1","(-1100,3900)","0","standard","I109";
;
CDS_LIB"standard"
BODY_TYPE"PLUMBING"
HDL_TAP"TRUE";
"B \NAC \NWC"14;
"S \NAC"
BN"21"134;
%"TAP"
"1","(-1100,3850)","0","standard","I110";
;
CDS_LIB"standard"
BODY_TYPE"PLUMBING"
HDL_TAP"TRUE";
"B \NAC \NWC"14;
"S \NAC"
BN"20"133;
%"TAP"
"1","(-1100,4050)","0","standard","I111";
;
CDS_LIB"standard"
BODY_TYPE"PLUMBING"
HDL_TAP"TRUE";
"B \NAC \NWC"14;
"S \NAC"
BN"24"137;
%"TAP"
"1","(-1100,4000)","0","standard","I112";
;
CDS_LIB"standard"
BODY_TYPE"PLUMBING"
HDL_TAP"TRUE";
"B \NAC \NWC"14;
"S \NAC"
BN"23"136;
%"TAP"
"1","(-1100,4200)","0","standard","I113";
;
CDS_LIB"standard"
BODY_TYPE"PLUMBING"
HDL_TAP"TRUE";
"B \NAC \NWC"14;
"S \NAC"
BN"27"140;
%"TAP"
"1","(-1100,4150)","0","standard","I114";
;
CDS_LIB"standard"
BODY_TYPE"PLUMBING"
HDL_TAP"TRUE";
"B \NAC \NWC"14;
"S \NAC"
BN"26"139;
%"TAP"
"1","(-1100,4100)","0","standard","I115";
;
CDS_LIB"standard"
BODY_TYPE"PLUMBING"
HDL_TAP"TRUE";
"B \NAC \NWC"14;
"S \NAC"
BN"25"138;
%"TAP"
"1","(-1100,4300)","0","standard","I116";
;
CDS_LIB"standard"
BODY_TYPE"PLUMBING"
HDL_TAP"TRUE";
"B \NAC \NWC"14;
"S \NAC"
BN"29"142;
%"TAP"
"1","(-1100,4250)","0","standard","I117";
;
CDS_LIB"standard"
BODY_TYPE"PLUMBING"
HDL_TAP"TRUE";
"B \NAC \NWC"14;
"S \NAC"
BN"28"141;
%"TAP"
"1","(-1100,4350)","0","standard","I118";
;
CDS_LIB"standard"
BODY_TYPE"PLUMBING"
HDL_TAP"TRUE";
"B \NAC \NWC"14;
"S \NAC"
BN"30"69;
%"TAP"
"1","(-1100,4400)","0","standard","I119";
;
CDS_LIB"standard"
BODY_TYPE"PLUMBING"
HDL_TAP"TRUE";
"B \NAC \NWC"14;
"S \NAC"
BN"31"70;
%"VCC_CORE"
"1","(-3575,2275)","0","logical_power","I12";
;
HDL_POWER"P3V3_AUX"
CDS_LIB"logical_power";
"A"1;
%"UNIVERSAL_GND"
"1","(625,150)","0","logical_power","I120";
;
CDS_LIB"logical_power"
HDL_POWER"GND";
"A"8;
%"UNIVERSAL_GND"
"1","(2250,150)","0","logical_power","I121";
;
CDS_LIB"logical_power"
HDL_POWER"GND";
"A"7;
%"Q_CAP"
"1","(625,525)","0","pure_quanta","I122";
;
PART_NUMBER"CH5221MEB00"
PACK_TYPE"C0402"
MATERIAL"X6S"
TOLERANCE"20%"
VALUE"2.2UF"
VOLTAGE"6.3V"
$LOCATION"C32"
CDS_LIB"pure_quanta"
CDS_LOCATION"C32"
$SEC"1"
CDS_SEC"1";
"B"
$PN"2"8;
"A"
$PN"1"3;
%"VCC_CORE"
"1","(625,850)","0","logical_power","I123";
;
HDL_POWER"P3V3_AUX"
CDS_LIB"logical_power";
"A"3;
%"Q_CAP"
"1","(1625,525)","0","pure_quanta","I127";
;
PART_NUMBER"CH6103KEA00"
PACK_TYPE"C0805"
TOLERANCE"10%"
VALUE"10UF"
VOLTAGE"16V"
MATERIAL"X6S"
$LOCATION"C33"
CDS_LIB"pure_quanta"
CDS_LOCATION"C33"
$SEC"1"
CDS_SEC"1";
"B"
$PN"2"7;
"A"
$PN"1"2;
%"VCC_CORE"
"1","(1625,850)","0","logical_power","I128";
;
HDL_POWER"P12V_S3_AUX_CPU0_NVDIMM"
CDS_LIB"logical_power";
"A"2;
%"TAP"
"1","(1825,2400)","0","standard","I129";
;
CDS_LIB"standard"
BODY_TYPE"PLUMBING"
HDL_TAP"TRUE";
"B \NAC \NWC"18;
"S \NAC"
BN"0"47;
%"Q_CAP"
"1","(2250,525)","0","pure_quanta","I130";
;
PART_NUMBER"CH6103KEA00"
PACK_TYPE"C0805"
TOLERANCE"10%"
VALUE"10UF"
VOLTAGE"16V"
MATERIAL"X6S"
$LOCATION"C34"
CDS_LIB"pure_quanta"
CDS_LOCATION"C34"
$SEC"1"
CDS_SEC"1";
"B"
$PN"2"7;
"A"
$PN"1"2;
%"TAP"
"1","(1650,2450)","0","standard","I131";
;
CDS_LIB"standard"
BODY_TYPE"PLUMBING"
HDL_TAP"TRUE";
"B \NAC \NWC"16;
"S \NAC"
BN"0"67;
%"TAP"
"1","(1650,2650)","0","standard","I132";
;
CDS_LIB"standard"
BODY_TYPE"PLUMBING"
HDL_TAP"TRUE";
"B \NAC \NWC"16;
"S \NAC"
BN"2"65;
%"TAP"
"1","(1650,2550)","0","standard","I133";
;
CDS_LIB"standard"
BODY_TYPE"PLUMBING"
HDL_TAP"TRUE";
"B \NAC \NWC"16;
"S \NAC"
BN"1"66;
%"TAP"
"1","(1650,2850)","0","standard","I134";
;
CDS_LIB"standard"
BODY_TYPE"PLUMBING"
HDL_TAP"TRUE";
"B \NAC \NWC"16;
"S \NAC"
BN"4"63;
%"TAP"
"1","(1650,2750)","0","standard","I135";
;
CDS_LIB"standard"
BODY_TYPE"PLUMBING"
HDL_TAP"TRUE";
"B \NAC \NWC"16;
"S \NAC"
BN"3"64;
%"TAP"
"1","(1825,2500)","0","standard","I136";
;
CDS_LIB"standard"
BODY_TYPE"PLUMBING"
HDL_TAP"TRUE";
"B \NAC \NWC"18;
"S \NAC"
BN"1"46;
%"TAP"
"1","(1825,2600)","0","standard","I137";
;
CDS_LIB"standard"
BODY_TYPE"PLUMBING"
HDL_TAP"TRUE";
"B \NAC \NWC"18;
"S \NAC"
BN"2"28;
%"TAP"
"1","(1825,2700)","0","standard","I138";
;
CDS_LIB"standard"
BODY_TYPE"PLUMBING"
HDL_TAP"TRUE";
"B \NAC \NWC"18;
"S \NAC"
BN"3"44;
%"TAP"
"1","(1825,2800)","0","standard","I139";
;
CDS_LIB"standard"
BODY_TYPE"PLUMBING"
HDL_TAP"TRUE";
"B \NAC \NWC"18;
"S \NAC"
BN"4"45;
%"TAP"
"1","(1825,2900)","0","standard","I140";
;
CDS_LIB"standard"
BODY_TYPE"PLUMBING"
HDL_TAP"TRUE";
"B \NAC \NWC"18;
"S \NAC"
BN"5"43;
%"TAP"
"1","(1650,2950)","0","standard","I141";
;
CDS_LIB"standard"
BODY_TYPE"PLUMBING"
HDL_TAP"TRUE";
"B \NAC \NWC"16;
"S \NAC"
BN"5"62;
%"TAP"
"1","(1650,3150)","0","standard","I142";
;
CDS_LIB"standard"
BODY_TYPE"PLUMBING"
HDL_TAP"TRUE";
"B \NAC \NWC"16;
"S \NAC"
BN"7"60;
%"TAP"
"1","(1650,3050)","0","standard","I143";
;
CDS_LIB"standard"
BODY_TYPE"PLUMBING"
HDL_TAP"TRUE";
"B \NAC \NWC"16;
"S \NAC"
BN"6"61;
%"TAP"
"1","(1650,3350)","0","standard","I144";
;
CDS_LIB"standard"
BODY_TYPE"PLUMBING"
HDL_TAP"TRUE";
"B \NAC \NWC"16;
"S \NAC"
BN"9"58;
%"TAP"
"1","(1650,3250)","0","standard","I145";
;
CDS_LIB"standard"
BODY_TYPE"PLUMBING"
HDL_TAP"TRUE";
"B \NAC \NWC"16;
"S \NAC"
BN"8"59;
%"TAP"
"1","(1825,3000)","0","standard","I146";
;
CDS_LIB"standard"
BODY_TYPE"PLUMBING"
HDL_TAP"TRUE";
"B \NAC \NWC"18;
"S \NAC"
BN"6"42;
%"TAP"
"1","(1825,3100)","0","standard","I147";
;
CDS_LIB"standard"
BODY_TYPE"PLUMBING"
HDL_TAP"TRUE";
"B \NAC \NWC"18;
"S \NAC"
BN"7"41;
%"TAP"
"1","(1825,3300)","0","standard","I148";
;
CDS_LIB"standard"
BODY_TYPE"PLUMBING"
HDL_TAP"TRUE";
"B \NAC \NWC"18;
"S \NAC"
BN"9"39;
%"TAP"
"1","(1825,3200)","0","standard","I149";
;
CDS_LIB"standard"
BODY_TYPE"PLUMBING"
HDL_TAP"TRUE";
"B \NAC \NWC"18;
"S \NAC"
BN"8"40;
%"TAP"
"1","(1650,3500)","0","standard","I150";
;
CDS_LIB"standard"
BODY_TYPE"PLUMBING"
HDL_TAP"TRUE";
"B \NAC \NWC"17;
"S \NAC"
BN"0"57;
%"TAP"
"1","(1650,3600)","0","standard","I151";
;
CDS_LIB"standard"
BODY_TYPE"PLUMBING"
HDL_TAP"TRUE";
"B \NAC \NWC"17;
"S \NAC"
BN"1"56;
%"TAP"
"1","(1650,3700)","0","standard","I152";
;
CDS_LIB"standard"
BODY_TYPE"PLUMBING"
HDL_TAP"TRUE";
"B \NAC \NWC"17;
"S \NAC"
BN"2"55;
%"TAP"
"1","(1650,3900)","0","standard","I153";
;
CDS_LIB"standard"
BODY_TYPE"PLUMBING"
HDL_TAP"TRUE";
"B \NAC \NWC"17;
"S \NAC"
BN"4"53;
%"TAP"
"1","(1650,3800)","0","standard","I154";
;
CDS_LIB"standard"
BODY_TYPE"PLUMBING"
HDL_TAP"TRUE";
"B \NAC \NWC"17;
"S \NAC"
BN"3"54;
%"TAP"
"1","(1825,3450)","0","standard","I155";
;
CDS_LIB"standard"
BODY_TYPE"PLUMBING"
HDL_TAP"TRUE";
"B \NAC \NWC"19;
"S \NAC"
BN"0"38;
%"TAP"
"1","(1825,3550)","0","standard","I156";
;
CDS_LIB"standard"
BODY_TYPE"PLUMBING"
HDL_TAP"TRUE";
"B \NAC \NWC"19;
"S \NAC"
BN"1"37;
%"TAP"
"1","(1825,3650)","0","standard","I157";
;
CDS_LIB"standard"
BODY_TYPE"PLUMBING"
HDL_TAP"TRUE";
"B \NAC \NWC"19;
"S \NAC"
BN"2"36;
%"TAP"
"1","(1825,3750)","0","standard","I158";
;
CDS_LIB"standard"
BODY_TYPE"PLUMBING"
HDL_TAP"TRUE";
"B \NAC \NWC"19;
"S \NAC"
BN"3"35;
%"TAP"
"1","(1825,3950)","0","standard","I159";
;
CDS_LIB"standard"
BODY_TYPE"PLUMBING"
HDL_TAP"TRUE";
"B \NAC \NWC"19;
"S \NAC"
BN"5"34;
%"TAP"
"1","(1825,3850)","0","standard","I160";
;
CDS_LIB"standard"
BODY_TYPE"PLUMBING"
HDL_TAP"TRUE";
"B \NAC \NWC"19;
"S \NAC"
BN"4"33;
%"TAP"
"1","(1650,4000)","0","standard","I161";
;
CDS_LIB"standard"
BODY_TYPE"PLUMBING"
HDL_TAP"TRUE";
"B \NAC \NWC"17;
"S \NAC"
BN"5"52;
%"TAP"
"1","(1650,4100)","0","standard","I162";
;
CDS_LIB"standard"
BODY_TYPE"PLUMBING"
HDL_TAP"TRUE";
"B \NAC \NWC"17;
"S \NAC"
BN"6"51;
%"TAP"
"1","(1650,4200)","0","standard","I163";
;
CDS_LIB"standard"
BODY_TYPE"PLUMBING"
HDL_TAP"TRUE";
"B \NAC \NWC"17;
"S \NAC"
BN"7"50;
%"TAP"
"1","(1650,4400)","0","standard","I164";
;
CDS_LIB"standard"
BODY_TYPE"PLUMBING"
HDL_TAP"TRUE";
"B \NAC \NWC"17;
"S \NAC"
BN"9"48;
%"TAP"
"1","(1650,4300)","0","standard","I165";
;
CDS_LIB"standard"
BODY_TYPE"PLUMBING"
HDL_TAP"TRUE";
"B \NAC \NWC"17;
"S \NAC"
BN"8"49;
%"TAP"
"1","(1825,4050)","0","standard","I166";
;
CDS_LIB"standard"
BODY_TYPE"PLUMBING"
HDL_TAP"TRUE";
"B \NAC \NWC"19;
"S \NAC"
BN"6"32;
%"TAP"
"1","(1825,4150)","0","standard","I167";
;
CDS_LIB"standard"
BODY_TYPE"PLUMBING"
HDL_TAP"TRUE";
"B \NAC \NWC"19;
"S \NAC"
BN"7"31;
%"TAP"
"1","(1825,4250)","0","standard","I168";
;
CDS_LIB"standard"
BODY_TYPE"PLUMBING"
HDL_TAP"TRUE";
"B \NAC \NWC"19;
"S \NAC"
BN"8"30;
%"TAP"
"1","(1825,4350)","0","standard","I169";
;
CDS_LIB"standard"
BODY_TYPE"PLUMBING"
HDL_TAP"TRUE";
"B \NAC \NWC"19;
"S \NAC"
BN"9"29;
%"UNIVERSAL_GND"
"1","(3325,700)","0","logical_power","I174";
;
CDS_LIB"logical_power"
HDL_POWER"GND";
"A"6;
%"SCONN288_ADR50017P130CC"
"3","(4175,2775)","0","pure_quanta","I175";
;
PART_NUMBER"DFHST8FS461"
VALUE"SCONN288_ADR50017-P130CC"
MATERIAL"IO"
PART_TYPE"SMLF"
$LOCATION"J11"
NEEDS_NO_SIZE"TRUE"
CDS_LMAN_SYM_OUTLINE"-450,1775,450,-1775"
CDS_LIB"pure_quanta"
CDS_LOCATION"J11"
$SEC"3"
CDS_SEC"3";
"G3"
$PN"G3"5;
"G2"
$PN"G2"5;
"G1"
$PN"G1"5;
"VSS62"
$PN"141"5;
"VSS61"
$PN"139"5;
"VSS60"
$PN"136"5;
"VSS58"
$PN"132"5;
"VSS104"
$PN"240"6;
"VSS102"
$PN"235"6;
"VSS100"
$PN"230"6;
"VIN_BULK2"
$PN"146"4;
"VIN_BULK1"
$PN"145"4;
"VIN_BULK0"
$PN"1"4;
"VSS126"
$PN"288"6;
"VSS125"
$PN"286"6;
"VSS124"
$PN"284"6;
"VSS123"
$PN"281"6;
"VSS122"
$PN"279"6;
"VSS121"
$PN"277"6;
"VSS120"
$PN"275"6;
"VSS119"
$PN"273"6;
"VSS118"
$PN"270"6;
"VSS117"
$PN"268"6;
"VSS116"
$PN"266"6;
"VSS115"
$PN"264"6;
"VSS114"
$PN"262"6;
"VSS113"
$PN"259"6;
"VSS112"
$PN"257"6;
"VSS111"
$PN"255"6;
"VSS110"
$PN"253"6;
"VSS109"
$PN"251"6;
"VSS108"
$PN"248"6;
"VSS107"
$PN"246"6;
"VSS106"
$PN"244"6;
"VSS105"
$PN"242"6;
"VSS103"
$PN"237"6;
"VSS101"
$PN"233"6;
"VSS99"
$PN"228"6;
"VSS98"
$PN"226"6;
"VSS97"
$PN"224"6;
"VSS96"
$PN"222"6;
"VSS95"
$PN"219"6;
"VSS94"
$PN"216"6;
"VSS93"
$PN"214"6;
"VSS92"
$PN"212"6;
"VSS91"
$PN"210"6;
"VSS90"
$PN"208"6;
"VSS89"
$PN"206"6;
"VSS88"
$PN"204"6;
"VSS87"
$PN"202"6;
"VSS86"
$PN"199"6;
"VSS85"
$PN"197"6;
"VSS84"
$PN"195"6;
"VSS83"
$PN"193"6;
"VSS82"
$PN"191"6;
"VSS81"
$PN"188"6;
"VSS80"
$PN"186"6;
"VSS79"
$PN"184"6;
"VSS78"
$PN"182"6;
"VSS77"
$PN"180"6;
"VSS76"
$PN"177"6;
"VSS75"
$PN"175"6;
"VSS74"
$PN"173"6;
"VSS73"
$PN"171"6;
"VSS72"
$PN"169"6;
"VSS71"
$PN"166"6;
"VSS70"
$PN"164"6;
"VSS69"
$PN"162"6;
"VSS68"
$PN"160"6;
"VSS67"
$PN"158"6;
"VSS66"
$PN"155"6;
"VSS65"
$PN"153"6;
"VSS64"
$PN"151"6;
"VSS63"
$PN"143"5;
"VSS59"
$PN"134"5;
"VSS57"
$PN"130"5;
"VSS56"
$PN"128"5;
"VSS55"
$PN"125"5;
"VSS54"
$PN"123"5;
"VSS53"
$PN"121"5;
"VSS52"
$PN"119"5;
"VSS51"
$PN"117"5;
"VSS50"
$PN"114"5;
"VSS49"
$PN"112"5;
"VSS48"
$PN"110"5;
"VSS47"
$PN"108"5;
"VSS46"
$PN"106"5;
"VSS45"
$PN"103"5;
"VSS44"
$PN"101"5;
"VSS43"
$PN"99"5;
"VSS42"
$PN"97"5;
"VSS41"
$PN"95"5;
"VSS40"
$PN"92"5;
"VSS39"
$PN"90"5;
"VSS38"
$PN"88"5;
"VSS37"
$PN"85"5;
"VSS36"
$PN"83"5;
"VSS35"
$PN"81"5;
"VSS34"
$PN"79"5;
"VSS33"
$PN"77"5;
"VSS32"
$PN"75"5;
"VSS31"
$PN"73"5;
"VSS30"
$PN"71"5;
"VSS29"
$PN"69"5;
"VSS28"
$PN"67"5;
"VSS27"
$PN"65"5;
"VSS26"
$PN"63"5;
"VSS25"
$PN"61"5;
"VSS24"
$PN"59"5;
"VSS23"
$PN"57"5;
"VSS22"
$PN"54"5;
"VSS21"
$PN"52"5;
"VSS20"
$PN"50"5;
"VSS19"
$PN"48"5;
"VSS18"
$PN"46"5;
"VSS17"
$PN"43"5;
"VSS16"
$PN"41"5;
"VSS15"
$PN"39"5;
"VSS14"
$PN"37"5;
"VSS13"
$PN"35"5;
"VSS12"
$PN"32"5;
"VSS11"
$PN"30"5;
"VSS10"
$PN"28"5;
"VSS9"
$PN"26"5;
"VSS8"
$PN"24"5;
"VSS7"
$PN"21"5;
"VSS6"
$PN"19"5;
"VSS5"
$PN"17"5;
"VSS4"
$PN"15"5;
"VSS3"
$PN"13"5;
"VSS2"
$PN"10"5;
"VSS1"
$PN"8"5;
"VSS0"
$PN"6"5;
%"UNIVERSAL_GND"
"1","(5025,700)","0","logical_power","I176";
;
CDS_LIB"logical_power"
HDL_POWER"GND";
"A"5;
%"VCC_CORE"
"1","(3325,4950)","0","logical_power","I177";
;
HDL_POWER"P12V_S3_AUX_CPU0_NVDIMM"
CDS_LIB"logical_power";
"A"4;
%"SCONN288_ADR50017P130CC"
"2","(750,3400)","0","pure_quanta","I178";
;
PART_NUMBER"DFHST8FS461"
MATERIAL"IO"
VALUE"SCONN288_ADR50017-P130CC"
PART_TYPE"SMLF"
LOCATION"J11"
CDS_LMAN_SYM_OUTLINE"-600,1150,600,-1150"
CDS_LIB"pure_quanta"
NEEDS_NO_SIZE"TRUE"
$SEC"2"
CDS_SEC"2";
"DQS7_A_C||TDQS7_A_C \B"
$PN"178"31;
"DQS6_A_T||TDQS6_A_T"
$PN"168"51;
"DQS8_B_T||TDQS8_B_T"
$PN"283"59;
"DQS8_B_C||TDQS8_B_C \B"
$PN"282"40;
"DQS7_B_T||TDQS7_B_T"
$PN"272"60;
"DQS0_A_C \B"
$PN"12"38;
"DQS0_A_T"
$PN"11"57;
"DQS0_B_C \B"
$PN"105"47;
"DQS0_B_T"
$PN"104"67;
"DQS1_A_C \B"
$PN"23"37;
"DQS1_A_T"
$PN"22"56;
"DQS1_B_C \B"
$PN"116"46;
"DQS1_B_T"
$PN"115"66;
"DQS2_A_C \B"
$PN"34"36;
"DQS2_A_T"
$PN"33"55;
"DQS2_B_C \B"
$PN"127"28;
"DQS2_B_T"
$PN"126"65;
"DQS3_A_C \B"
$PN"45"35;
"DQS3_A_T"
$PN"44"54;
"DQS3_B_C \B"
$PN"138"44;
"DQS3_B_T"
$PN"137"64;
"DQS4_A_C \B"
$PN"56"33;
"DQS4_A_T"
$PN"55"53;
"DQS4_B_C \B"
$PN"238"45;
"DQS4_B_T"
$PN"239"63;
"DQS5_A_C||TDQS5_A_C||DQS5_A_T||TDQS5_A_T \B"
$PN"156"34;
"DQS5_A_T||TDQS5_A_T"
$PN"157"52;
"DQS5_B_C||TDQS5_B_C \B"
$PN"249"43;
"DQS5_B_T||TDQS5_B_T"
$PN"250"62;
"DQS6_A_C||TDQS6_A_C||DQS6_A_T||TDQS6_A_T \B"
$PN"167"32;
"DQS6_B_C||TDQS6_B_C \B"
$PN"260"42;
"DQS6_B_T||TDQS6_B_T"
$PN"261"61;
"DQS7_A_T||TDQS7_A_T"
$PN"179"50;
"DQS7_B_C||TDQS7_B_C \B"
$PN"271"41;
"DQS8_A_C||TDQS8_A_C \B"
$PN"189"30;
"DQS8_A_T||TDQS8_A_T"
$PN"190"49;
"DQS9_A_C||TDQS9_A_C \B"
$PN"200"29;
"DQS9_A_T||TDQS9_A_T"
$PN"201"48;
"DQS9_B_C||TDQS9_B_C \B"
$PN"94"39;
"DQS9_B_T||TDQS9_B_T||DBI4_B_N"
$PN"93"58;
%"Q_RES"
"1","(-3725,1700)","0","pure_quanta","I179";
;
PART_NUMBER"CS04992FB07"
MATERIAL"CHIP"
VALUE"49.9"
$LOCATION"R3885"
CDS_LIB"pure_quanta"
PACK_TYPE"0402LF"
TOLERANCE"1%"
WATTAGE"1/16W"
CDS_LOCATION"R3885"
$SEC"1"
CDS_SEC"1";
"B"
$PN"2"25;
"A"
$PN"1"22;
%"Q_RES"
"2","(-2525,250)","0","pure_quanta","I2";
;
PART_NUMBER"CS32322FB03"
VALUE"23.2K"
TOLERANCE"1%"
WATTAGE"1/16W"
MATERIAL"CHIP"
PACK_TYPE"0402LF"
$LOCATION"R36"
CDS_LIB"pure_quanta"
CDS_LOCATION"R36"
$SEC"1"
CDS_SEC"1";
"A"
$PN"1"178;
"B"
$PN"2"9;
%"SCONN288_ADR50017P130CC"
"1","(-1925,2675)","0","pure_quanta","I25";
;
PART_NUMBER"DFHST8FS461"
MATERIAL"IO"
PART_TYPE"SMLF"
VALUE"SCONN288_ADR50017-P130CC"
$LOCATION"J11"
NEEDS_NO_SIZE"TRUE"
CDS_LMAN_SYM_OUTLINE"-450,1875,450,-1875"
CDS_LIB"pure_quanta"
CDS_LOCATION"J11"
$SEC"1"
CDS_SEC"1";
"DQ31_A"
$PN"194"70;
"CB7_A"
$PN"205"177;
"CB4_A"
$PN"58"73;
"CB1_A"
$PN"53"176;
"CB7_B"
$PN"236"175;
"ALERT_N \B"
$PN"62"23;
"CA0_A"
$PN"66"174;
"CA0_B"
$PN"76"173;
"CA1_A"
$PN"211"172;
"CA1_B"
$PN"221"171;
"CA2_A"
$PN"68"170;
"CA2_B"
$PN"78"169;
"CA3_A"
$PN"213"168;
"CA3_B"
$PN"223"167;
"CA4_A"
$PN"70"166;
"CA4_B"
$PN"80"165;
"CA5_A"
$PN"215"164;
"CA5_B"
$PN"225"163;
"CA6_A"
$PN"72"162;
"CA6_B"
$PN"82"161;
"CB6_A"
$PN"203"160;
"CB5_A"
$PN"60"159;
"CB3_A"
$PN"198"158;
"CB2_A"
$PN"196"157;
"CB0_A"
$PN"51"156;
"CB6_B"
$PN"234"155;
"CB5_B"
$PN"91"154;
"CB4_B"
$PN"89"153;
"CB3_B"
$PN"243"152;
"CB2_B"
$PN"241"151;
"CB1_B"
$PN"98"150;
"CB0_B"
$PN"96"149;
"CK_C \B"
$PN"218"148;
"CK_T"
$PN"217"147;
"CS0_A_N"
$PN"64"146;
"CS0_B_N"
$PN"84"145;
"CS1_A_N"
$PN"209"144;
"CS1_B_N"
$PN"229"143;
"DQ30_A"
$PN"192"69;
"DQ29_A"
$PN"49"142;
"DQ28_A"
$PN"47"141;
"DQ27_A"
$PN"187"140;
"DQ26_A"
$PN"185"139;
"DQ25_A"
$PN"42"138;
"DQ24_A"
$PN"40"137;
"DQ23_A"
$PN"183"136;
"DQ22_A"
$PN"181"135;
"DQ21_A"
$PN"38"134;
"DQ20_A"
$PN"36"133;
"DQ19_A"
$PN"176"132;
"DQ18_A"
$PN"174"131;
"DQ17_A"
$PN"31"130;
"DQ16_A"
$PN"29"129;
"DQ15_A"
$PN"172"128;
"DQ14_A"
$PN"170"127;
"DQ13_A"
$PN"27"126;
"DQ12_A"
$PN"25"72;
"DQ11_A"
$PN"165"125;
"DQ10_A"
$PN"163"124;
"DQ9_A"
$PN"20"71;
"DQ8_A"
$PN"18"123;
"DQ7_A"
$PN"161"122;
"DQ6_A"
$PN"159"121;
"DQ5_A"
$PN"16"120;
"DQ4_A"
$PN"14"119;
"DQ3_A"
$PN"154"118;
"DQ2_A"
$PN"152"117;
"DQ1_A"
$PN"9"116;
"DQ0_A"
$PN"7"115;
"DQ31_B"
$PN"287"114;
"DQ30_B"
$PN"285"113;
"DQ29_B"
$PN"142"112;
"DQ28_B"
$PN"140"111;
"DQ27_B"
$PN"280"110;
"DQ26_B"
$PN"278"109;
"DQ25_B"
$PN"135"108;
"DQ24_B"
$PN"133"107;
"DQ23_B"
$PN"276"106;
"DQ22_B"
$PN"274"105;
"DQ21_B"
$PN"131"104;
"DQ20_B"
$PN"129"103;
"DQ19_B"
$PN"269"74;
"DQ18_B"
$PN"267"102;
"DQ17_B"
$PN"124"101;
"DQ16_B"
$PN"122"100;
"DQ15_B"
$PN"265"99;
"DQ14_B"
$PN"263"98;
"DQ13_B"
$PN"120"97;
"DQ12_B"
$PN"118"96;
"DQ11_B"
$PN"258"95;
"DQ10_B"
$PN"256"94;
"DQ9_B"
$PN"113"93;
"DQ8_B"
$PN"111"92;
"DQ7_B"
$PN"254"91;
"DQ6_B"
$PN"252"75;
"DQ5_B"
$PN"109"90;
"DQ4_B"
$PN"107"89;
"DQ3_B"
$PN"247"88;
"DQ2_B"
$PN"245"87;
"DQ1_B"
$PN"102"78;
"DQ0_B"
$PN"100"86;
"HSA"
$PN"148"20;
"HSCL"
$PN"4"22;
"HSDA"
$PN"5"21;
"LBD||RSP_A_N"
$PN"86"85;
"LBS||RSP_B_N"
$PN"87"77;
"PAR_A"
$PN"74"84;
"PAR_B"
$PN"227"83;
"PWR_GOOD||FAIL_N"
$PN"147"26;
"RESET_N \B"
$PN"207"24;
"RFU6"
$PN"232"27;
"RFU5"
$PN"231"82;
"RFU4"
$PN"220"81;
"RFU3"
$PN"150"68;
"RFU2"
$PN"149"80;
"RFU1"
$PN"144"79;
"RFU0"
$PN"2"76;
"VIN_MGMT"
$PN"3"1;
%"TAP"
"1","(-2750,2350)","2","standard","I26";
;
CDS_LIB"standard"
BODY_TYPE"PLUMBING"
HDL_TAP"TRUE";
"B \NAC \NWC"11;
"S \NAC"
BN"3"152;
%"TAP"
"1","(-2750,2300)","2","standard","I27";
;
CDS_LIB"standard"
BODY_TYPE"PLUMBING"
HDL_TAP"TRUE";
"B \NAC \NWC"11;
"S \NAC"
BN"2"151;
%"TAP"
"1","(-2750,2200)","2","standard","I28";
;
CDS_LIB"standard"
BODY_TYPE"PLUMBING"
HDL_TAP"TRUE";
"B \NAC \NWC"11;
"S \NAC"
BN"0"149;
%"TAP"
"1","(-2750,2250)","2","standard","I29";
;
CDS_LIB"standard"
BODY_TYPE"PLUMBING"
HDL_TAP"TRUE";
"B \NAC \NWC"11;
"S \NAC"
BN"1"150;
%"TAP"
"1","(-2750,2400)","2","standard","I30";
;
CDS_LIB"standard"
BODY_TYPE"PLUMBING"
HDL_TAP"TRUE";
"B \NAC \NWC"11;
"S \NAC"
BN"4"153;
%"TAP"
"1","(-1100,1250)","0","standard","I31";
;
CDS_LIB"standard"
BODY_TYPE"PLUMBING"
HDL_TAP"TRUE";
"B \NAC \NWC"15;
"S \NAC"
BN"1"78;
%"TAP"
"1","(-1100,1200)","0","standard","I32";
;
CDS_LIB"standard"
BODY_TYPE"PLUMBING"
HDL_TAP"TRUE";
"B \NAC \NWC"15;
"S \NAC"
BN"0"86;
%"TAP"
"1","(-1100,1300)","0","standard","I33";
;
CDS_LIB"standard"
BODY_TYPE"PLUMBING"
HDL_TAP"TRUE";
"B \NAC \NWC"15;
"S \NAC"
BN"2"87;
%"TAP"
"1","(-1100,1350)","0","standard","I34";
;
CDS_LIB"standard"
BODY_TYPE"PLUMBING"
HDL_TAP"TRUE";
"B \NAC \NWC"15;
"S \NAC"
BN"3"88;
%"TAP"
"1","(-1100,1400)","0","standard","I35";
;
CDS_LIB"standard"
BODY_TYPE"PLUMBING"
HDL_TAP"TRUE";
"B \NAC \NWC"15;
"S \NAC"
BN"4"89;
%"TAP"
"1","(-1100,1450)","0","standard","I36";
;
CDS_LIB"standard"
BODY_TYPE"PLUMBING"
HDL_TAP"TRUE";
"B \NAC \NWC"15;
"S \NAC"
BN"5"90;
%"TAP"
"1","(-1100,1500)","0","standard","I37";
;
CDS_LIB"standard"
BODY_TYPE"PLUMBING"
HDL_TAP"TRUE";
"B \NAC \NWC"15;
"S \NAC"
BN"6"75;
%"TAP"
"1","(-1100,1650)","0","standard","I38";
;
CDS_LIB"standard"
BODY_TYPE"PLUMBING"
HDL_TAP"TRUE";
"B \NAC \NWC"15;
"S \NAC"
BN"9"93;
%"TAP"
"1","(-1100,1600)","0","standard","I39";
;
CDS_LIB"standard"
BODY_TYPE"PLUMBING"
HDL_TAP"TRUE";
"B \NAC \NWC"15;
"S \NAC"
BN"8"92;
%"TAP"
"1","(-1100,1550)","0","standard","I40";
;
CDS_LIB"standard"
BODY_TYPE"PLUMBING"
HDL_TAP"TRUE";
"B \NAC \NWC"15;
"S \NAC"
BN"7"91;
%"TAP"
"1","(-1100,1750)","0","standard","I41";
;
CDS_LIB"standard"
BODY_TYPE"PLUMBING"
HDL_TAP"TRUE";
"B \NAC \NWC"15;
"S \NAC"
BN"11"95;
%"TAP"
"1","(-1100,1700)","0","standard","I42";
;
CDS_LIB"standard"
BODY_TYPE"PLUMBING"
HDL_TAP"TRUE";
"B \NAC \NWC"15;
"S \NAC"
BN"10"94;
%"TAP"
"1","(-1100,1900)","0","standard","I43";
;
CDS_LIB"standard"
BODY_TYPE"PLUMBING"
HDL_TAP"TRUE";
"B \NAC \NWC"15;
"S \NAC"
BN"14"98;
%"TAP"
"1","(-1100,1850)","0","standard","I44";
;
CDS_LIB"standard"
BODY_TYPE"PLUMBING"
HDL_TAP"TRUE";
"B \NAC \NWC"15;
"S \NAC"
BN"13"97;
%"TAP"
"1","(-1100,1800)","0","standard","I45";
;
CDS_LIB"standard"
BODY_TYPE"PLUMBING"
HDL_TAP"TRUE";
"B \NAC \NWC"15;
"S \NAC"
BN"12"96;
%"TAP"
"1","(-1100,2000)","0","standard","I46";
;
CDS_LIB"standard"
BODY_TYPE"PLUMBING"
HDL_TAP"TRUE";
"B \NAC \NWC"15;
"S \NAC"
BN"16"100;
%"TAP"
"1","(-1100,1950)","0","standard","I47";
;
CDS_LIB"standard"
BODY_TYPE"PLUMBING"
HDL_TAP"TRUE";
"B \NAC \NWC"15;
"S \NAC"
BN"15"99;
%"TAP"
"1","(-1100,2150)","0","standard","I48";
;
CDS_LIB"standard"
BODY_TYPE"PLUMBING"
HDL_TAP"TRUE";
"B \NAC \NWC"15;
"S \NAC"
BN"19"74;
%"TAP"
"1","(-1100,2100)","0","standard","I49";
;
CDS_LIB"standard"
BODY_TYPE"PLUMBING"
HDL_TAP"TRUE";
"B \NAC \NWC"15;
"S \NAC"
BN"18"102;
%"TAP"
"1","(-1100,2050)","0","standard","I50";
;
CDS_LIB"standard"
BODY_TYPE"PLUMBING"
HDL_TAP"TRUE";
"B \NAC \NWC"15;
"S \NAC"
BN"17"101;
%"TAP"
"1","(-1100,2200)","0","standard","I51";
;
CDS_LIB"standard"
BODY_TYPE"PLUMBING"
HDL_TAP"TRUE";
"B \NAC \NWC"15;
"S \NAC"
BN"20"103;
%"TAP"
"1","(-1100,2250)","0","standard","I52";
;
CDS_LIB"standard"
BODY_TYPE"PLUMBING"
HDL_TAP"TRUE";
"B \NAC \NWC"15;
"S \NAC"
BN"21"104;
%"TAP"
"1","(-1100,2300)","0","standard","I53";
;
CDS_LIB"standard"
BODY_TYPE"PLUMBING"
HDL_TAP"TRUE";
"B \NAC \NWC"15;
"S \NAC"
BN"22"105;
%"TAP"
"1","(-1100,2400)","0","standard","I54";
;
CDS_LIB"standard"
BODY_TYPE"PLUMBING"
HDL_TAP"TRUE";
"B \NAC \NWC"15;
"S \NAC"
BN"24"107;
%"TAP"
"1","(-1100,2350)","0","standard","I55";
;
CDS_LIB"standard"
BODY_TYPE"PLUMBING"
HDL_TAP"TRUE";
"B \NAC \NWC"15;
"S \NAC"
BN"23"106;
%"TAP"
"1","(-2750,2500)","2","standard","I56";
;
CDS_LIB"standard"
BODY_TYPE"PLUMBING"
HDL_TAP"TRUE";
"B \NAC \NWC"11;
"S \NAC"
BN"6"155;
%"TAP"
"1","(-2750,2450)","2","standard","I57";
;
CDS_LIB"standard"
BODY_TYPE"PLUMBING"
HDL_TAP"TRUE";
"B \NAC \NWC"11;
"S \NAC"
BN"5"154;
%"TAP"
"1","(-2750,2650)","2","standard","I58";
;
CDS_LIB"standard"
BODY_TYPE"PLUMBING"
HDL_TAP"TRUE";
"B \NAC \NWC"10;
"S \NAC"
BN"0"156;
%"TAP"
"1","(-2750,2550)","2","standard","I59";
;
CDS_LIB"standard"
BODY_TYPE"PLUMBING"
HDL_TAP"TRUE";
"B \NAC \NWC"11;
"S \NAC"
BN"7"175;
%"TAP"
"1","(-2750,2700)","2","standard","I60";
;
CDS_LIB"standard"
BODY_TYPE"PLUMBING"
HDL_TAP"TRUE";
"B \NAC \NWC"10;
"S \NAC"
BN"1"176;
%"TAP"
"1","(-2750,2750)","2","standard","I61";
;
CDS_LIB"standard"
BODY_TYPE"PLUMBING"
HDL_TAP"TRUE";
"B \NAC \NWC"10;
"S \NAC"
BN"2"157;
%"TAP"
"1","(-2750,2800)","2","standard","I62";
;
CDS_LIB"standard"
BODY_TYPE"PLUMBING"
HDL_TAP"TRUE";
"B \NAC \NWC"10;
"S \NAC"
BN"3"158;
%"TAP"
"1","(-2750,2900)","2","standard","I63";
;
CDS_LIB"standard"
BODY_TYPE"PLUMBING"
HDL_TAP"TRUE";
"B \NAC \NWC"10;
"S \NAC"
BN"5"159;
%"TAP"
"1","(-2750,2850)","2","standard","I64";
;
CDS_LIB"standard"
BODY_TYPE"PLUMBING"
HDL_TAP"TRUE";
"B \NAC \NWC"10;
"S \NAC"
BN"4"73;
%"TAP"
"1","(-2750,3000)","2","standard","I65";
;
CDS_LIB"standard"
BODY_TYPE"PLUMBING"
HDL_TAP"TRUE";
"B \NAC \NWC"10;
"S \NAC"
BN"7"177;
%"TAP"
"1","(-2750,2950)","2","standard","I66";
;
CDS_LIB"standard"
BODY_TYPE"PLUMBING"
HDL_TAP"TRUE";
"B \NAC \NWC"10;
"S \NAC"
BN"6"160;
%"TAP"
"1","(-2750,3700)","2","standard","I67";
;
CDS_LIB"standard"
BODY_TYPE"PLUMBING"
HDL_TAP"TRUE";
"B \NAC \NWC"13;
"S \NAC"
BN"0"173;
%"TAP"
"1","(-2750,3750)","2","standard","I68";
;
CDS_LIB"standard"
BODY_TYPE"PLUMBING"
HDL_TAP"TRUE";
"B \NAC \NWC"13;
"S \NAC"
BN"1"171;
%"TAP"
"1","(-2750,3800)","2","standard","I69";
;
CDS_LIB"standard"
BODY_TYPE"PLUMBING"
HDL_TAP"TRUE";
"B \NAC \NWC"13;
"S \NAC"
BN"2"169;
%"TAP"
"1","(-2750,3850)","2","standard","I70";
;
CDS_LIB"standard"
BODY_TYPE"PLUMBING"
HDL_TAP"TRUE";
"B \NAC \NWC"13;
"S \NAC"
BN"3"167;
%"TAP"
"1","(-2750,3900)","2","standard","I71";
;
CDS_LIB"standard"
BODY_TYPE"PLUMBING"
HDL_TAP"TRUE";
"B \NAC \NWC"13;
"S \NAC"
BN"4"165;
%"TAP"
"1","(-2750,3950)","2","standard","I72";
;
CDS_LIB"standard"
BODY_TYPE"PLUMBING"
HDL_TAP"TRUE";
"B \NAC \NWC"13;
"S \NAC"
BN"5"163;
%"TAP"
"1","(-2750,4000)","2","standard","I73";
;
CDS_LIB"standard"
BODY_TYPE"PLUMBING"
HDL_TAP"TRUE";
"B \NAC \NWC"13;
"S \NAC"
BN"6"161;
%"TAP"
"1","(-2750,4150)","2","standard","I74";
;
CDS_LIB"standard"
BODY_TYPE"PLUMBING"
HDL_TAP"TRUE";
"B \NAC \NWC"12;
"S \NAC"
BN"1"172;
%"TAP"
"1","(-2750,4100)","2","standard","I75";
;
CDS_LIB"standard"
BODY_TYPE"PLUMBING"
HDL_TAP"TRUE";
"B \NAC \NWC"12;
"S \NAC"
BN"0"174;
%"TAP"
"1","(-2750,4200)","2","standard","I76";
;
CDS_LIB"standard"
BODY_TYPE"PLUMBING"
HDL_TAP"TRUE";
"B \NAC \NWC"12;
"S \NAC"
BN"2"170;
%"TAP"
"1","(-2750,4250)","2","standard","I77";
;
CDS_LIB"standard"
BODY_TYPE"PLUMBING"
HDL_TAP"TRUE";
"B \NAC \NWC"12;
"S \NAC"
BN"3"168;
%"TAP"
"1","(-2750,4300)","2","standard","I78";
;
CDS_LIB"standard"
BODY_TYPE"PLUMBING"
HDL_TAP"TRUE";
"B \NAC \NWC"12;
"S \NAC"
BN"4"166;
%"TAP"
"1","(-2750,4350)","2","standard","I79";
;
CDS_LIB"standard"
BODY_TYPE"PLUMBING"
HDL_TAP"TRUE";
"B \NAC \NWC"12;
"S \NAC"
BN"5"164;
%"TAP"
"1","(-2750,4400)","2","standard","I80";
;
CDS_LIB"standard"
BODY_TYPE"PLUMBING"
HDL_TAP"TRUE";
"B \NAC \NWC"12;
"S \NAC"
BN"6"162;
%"TAP"
"1","(-1100,2550)","0","standard","I81";
;
CDS_LIB"standard"
BODY_TYPE"PLUMBING"
HDL_TAP"TRUE";
"B \NAC \NWC"15;
"S \NAC"
BN"27"110;
%"TAP"
"1","(-1100,2500)","0","standard","I82";
;
CDS_LIB"standard"
BODY_TYPE"PLUMBING"
HDL_TAP"TRUE";
"B \NAC \NWC"15;
"S \NAC"
BN"26"109;
%"TAP"
"1","(-1100,2450)","0","standard","I83";
;
CDS_LIB"standard"
BODY_TYPE"PLUMBING"
HDL_TAP"TRUE";
"B \NAC \NWC"15;
"S \NAC"
BN"25"108;
%"TAP"
"1","(-1100,2650)","0","standard","I84";
;
CDS_LIB"standard"
BODY_TYPE"PLUMBING"
HDL_TAP"TRUE";
"B \NAC \NWC"15;
"S \NAC"
BN"29"112;
%"TAP"
"1","(-1100,2600)","0","standard","I85";
;
CDS_LIB"standard"
BODY_TYPE"PLUMBING"
HDL_TAP"TRUE";
"B \NAC \NWC"15;
"S \NAC"
BN"28"111;
%"TAP"
"1","(-1100,2750)","0","standard","I86";
;
CDS_LIB"standard"
BODY_TYPE"PLUMBING"
HDL_TAP"TRUE";
"B \NAC \NWC"15;
"S \NAC"
BN"31"114;
%"TAP"
"1","(-1100,2700)","0","standard","I87";
;
CDS_LIB"standard"
BODY_TYPE"PLUMBING"
HDL_TAP"TRUE";
"B \NAC \NWC"15;
"S \NAC"
BN"30"113;
%"TAP"
"1","(-1100,2850)","0","standard","I88";
;
CDS_LIB"standard"
BODY_TYPE"PLUMBING"
HDL_TAP"TRUE";
"B \NAC \NWC"14;
"S \NAC"
BN"0"115;
%"TAP"
"1","(-1100,2900)","0","standard","I89";
;
CDS_LIB"standard"
BODY_TYPE"PLUMBING"
HDL_TAP"TRUE";
"B \NAC \NWC"14;
"S \NAC"
BN"1"116;
%"TAP"
"1","(-1100,3050)","0","standard","I90";
;
CDS_LIB"standard"
BODY_TYPE"PLUMBING"
HDL_TAP"TRUE";
"B \NAC \NWC"14;
"S \NAC"
BN"4"119;
%"TAP"
"1","(-1100,3000)","0","standard","I91";
;
CDS_LIB"standard"
BODY_TYPE"PLUMBING"
HDL_TAP"TRUE";
"B \NAC \NWC"14;
"S \NAC"
BN"3"118;
%"TAP"
"1","(-1100,2950)","0","standard","I92";
;
CDS_LIB"standard"
BODY_TYPE"PLUMBING"
HDL_TAP"TRUE";
"B \NAC \NWC"14;
"S \NAC"
BN"2"117;
%"TAP"
"1","(-1100,3150)","0","standard","I93";
;
CDS_LIB"standard"
BODY_TYPE"PLUMBING"
HDL_TAP"TRUE";
"B \NAC \NWC"14;
"S \NAC"
BN"6"121;
%"TAP"
"1","(-1100,3100)","0","standard","I94";
;
CDS_LIB"standard"
BODY_TYPE"PLUMBING"
HDL_TAP"TRUE";
"B \NAC \NWC"14;
"S \NAC"
BN"5"120;
%"TAP"
"1","(-1100,3300)","0","standard","I95";
;
CDS_LIB"standard"
BODY_TYPE"PLUMBING"
HDL_TAP"TRUE";
"B \NAC \NWC"14;
"S \NAC"
BN"9"71;
%"TAP"
"1","(-1100,3200)","0","standard","I96";
;
CDS_LIB"standard"
BODY_TYPE"PLUMBING"
HDL_TAP"TRUE";
"B \NAC \NWC"14;
"S \NAC"
BN"7"122;
%"TAP"
"1","(-1100,3250)","0","standard","I97";
;
CDS_LIB"standard"
BODY_TYPE"PLUMBING"
HDL_TAP"TRUE";
"B \NAC \NWC"14;
"S \NAC"
BN"8"123;
%"TAP"
"1","(-1100,3350)","0","standard","I98";
;
CDS_LIB"standard"
BODY_TYPE"PLUMBING"
HDL_TAP"TRUE";
"B \NAC \NWC"14;
"S \NAC"
BN"10"124;
%"TAP"
"1","(-1100,3400)","0","standard","I99";
;
CDS_LIB"standard"
BODY_TYPE"PLUMBING"
HDL_TAP"TRUE";
"B \NAC \NWC"14;
"S \NAC"
BN"11"125;
END.
